# BASEBOARD_FAB2 (Tioga Pass) — schematic netlist excerpt (pin names and nets, part order shuffled) for the footprints in the layout excerpt that follows; sources: Cadence DE-HDL packaged netlist, KiCad conversion of Wiwynn_Tioga_Pass_MB.brd

R8G24  RES  22.1 1.0% CHIP  pkg 0402  page 101 : A = CLK_50M_CKMNG_PCH_10GBE_R ; B = CLK_50M_CKMNG_PCH_10GBE
R2N25  RES  51.1 1.0% CHIP  pkg 0402  page 157 : A = FM_NMI_EVENT_N ; B = FM_BMC_NMI_N
R1C7  RES  0.0 5% CHIP  pkg 0402  page 210 : A = VSENSE_PVSA_CPU1_P ; B = VSENSE_PVSA_CPU1_SKT_VSEN

(kicad_pcb
	(version 20260206)
	(generator "pcbnew")
	(generator_version "10.0")
	(general
		(thickness 1.6)
		(legacy_teardrops no)
	)
	(paper "A4")
	(title_block
		(title "Wiwynn_Tioga_Pass_MB.brd")
		(comment 1 "Tioga Pass / footprints 1072-1074 of 4770")
	)
	(layers
		(0 "F.Cu" signal "TOP")
		(4 "In1.Cu" signal "L2GND")
		(6 "In2.Cu" signal "L3")
		(8 "In3.Cu" signal "L4GND")
		(10 "In4.Cu" signal "L5")
		(12 "In5.Cu" signal "L6GND")
		(14 "In6.Cu" signal "L7VCC")
		(16 "In7.Cu" signal "L8VCC")
		(18 "In8.Cu" signal "L9GND")
		(20 "In9.Cu" signal "L10")
		(22 "In10.Cu" signal "L11GND")
		(24 "In11.Cu" signal "L12")
		(26 "In12.Cu" signal "L13GND")
		(2 "B.Cu" signal "BOTTOM")
		(9 "F.Adhes" user "F.Adhesive")
		(11 "B.Adhes" user "B.Adhesive")
		(13 "F.Paste" user "Package Geometry/Pastemask Top")
		(15 "B.Paste" user "Package Geometry/Pastemask Bottom")
		(5 "F.SilkS" user "Ref Des/Silkscreen Top")
		(7 "B.SilkS" user "Ref Des/Silkscreen Bottom")
		(1 "F.Mask" user "Board Geometry/Soldermask Top")
		(3 "B.Mask" user "Board Geometry/Soldermask Bottom")
		(17 "Dwgs.User" user "User.Drawings")
		(19 "Cmts.User" user "User.Comments")
		(21 "Eco1.User" user "User.Eco1")
		(23 "Eco2.User" user "User.Eco2")
		(25 "Edge.Cuts" user "Board Geometry/Outline")
		(27 "Margin" user)
		(31 "F.CrtYd" user "Package Geometry/Place Bound Top")
		(29 "B.CrtYd" user "Package Geometry/Place Bound Bottom")
		(35 "F.Fab" user "Ref Des/Assembly Top")
		(33 "B.Fab" user "Ref Des/Assembly Bottom")
	)
	(footprint ""
		(layer "F.Cu")
		(at 396.367 -85.09 180)
		(property "Reference" "R2N25"
			(at 0 0 180)
			(layer "F.SilkS")
			(hide yes)
			(effects
				(font
					(size 1.27 1.27)
				)
			)
		)
		(property "Value" ""
			(at 0 0 180)
			(layer "F.Fab")
			(effects
				(font
					(size 1.27 1.27)
				)
			)
		)
		(duplicate_pad_numbers_are_jumpers no)
		(fp_poly
			(pts
				(xy -0.2794 -0.1016) (xy 0.2794 -0.1016) (xy 0.2794 0.9906) (xy -0.2794 0.9906)
			)
			(stroke
				(width 0)
				(type default)
			)
			(fill no)
			(layer "F.CrtYd")
		)
		(fp_line
			(start 0.2794 0.9906)
			(end 0.2794 -0.1016)
			(stroke
				(width 0.1)
				(type default)
			)
			(layer "F.Fab")
		)
		(fp_line
			(start 0.2794 -0.1016)
			(end -0.2794 -0.1016)
			(stroke
				(width 0.1)
				(type default)
			)
			(layer "F.Fab")
		)
		(fp_line
			(start -0.2794 0.9906)
			(end 0.2794 0.9906)
			(stroke
				(width 0.1)
				(type default)
			)
			(layer "F.Fab")
		)
		(fp_line
			(start -0.2794 -0.1016)
			(end -0.2794 0.9906)
			(stroke
				(width 0.1)
				(type default)
			)
			(layer "F.Fab")
		)
		(pad "1" smd rect
			(at 0 0 180)
			(size 0.508 0.508)
			(layers "F.Cu" "F.Mask" "F.Paste")
			(net "FM_NMI_EVENT_N")
		)
		(pad "2" smd rect
			(at 0 0.889 180)
			(size 0.508 0.508)
			(layers "F.Cu" "F.Mask" "F.Paste")
			(net "FM_BMC_NMI_N")
		)
		(zone
			(layer "F.Cu")
			(hatch none 0.5)
			(connect_pads
				(clearance 0)
			)
			(min_thickness 0.25)
			(keepout
				(tracks not_allowed)
				(vias allowed)
				(pads allowed)
				(copperpour not_allowed)
				(footprints allowed)
			)
			(placement
				(enabled no)
				(sheetname "")
			)
			(fill
				(thermal_gap 0.5)
				(thermal_bridge_width 0.5)
				(island_removal_mode 0)
			)
			(polygon
				(pts
					(xy 396.621 -85.725) (xy 396.113 -85.725) (xy 396.113 -85.344) (xy 396.621 -85.344)
				)
			)
		)
		(zone
			(layer "F.Cu")
			(hatch none 0.5)
			(connect_pads
				(clearance 0)
			)
			(min_thickness 0.25)
			(keepout
				(tracks allowed)
				(vias not_allowed)
				(pads allowed)
				(copperpour not_allowed)
				(footprints allowed)
			)
			(placement
				(enabled no)
				(sheetname "")
			)
			(fill
				(thermal_gap 0.5)
				(thermal_bridge_width 0.5)
				(island_removal_mode 0)
			)
			(polygon
				(pts
					(xy 396.621 -85.344) (xy 396.113 -85.344) (xy 396.113 -85.725) (xy 396.621 -85.725)
				)
			)
		)
	)
	(footprint ""
		(layer "F.Cu")
		(at 40.60825 -102.729284 90)
		(property "Reference" "R1C7"
			(at -0.8382 -0.67818 90)
			(unlocked yes)
			(layer "F.SilkS")
			(effects
				(font
					(size 0.4064 0.254)
					(thickness 0.1524)
				)
				(justify left)
			)
		)
		(property "Value" ""
			(at 0 0 90)
			(layer "F.Fab")
			(effects
				(font
					(size 1.27 1.27)
				)
			)
		)
		(duplicate_pad_numbers_are_jumpers no)
		(fp_poly
			(pts
				(xy -0.2794 -0.1016) (xy 0.2794 -0.1016) (xy 0.2794 0.9906) (xy -0.2794 0.9906)
			)
			(stroke
				(width 0)
				(type default)
			)
			(fill no)
			(layer "F.CrtYd")
		)
		(fp_line
			(start 0.2794 -0.1016)
			(end -0.2794 -0.1016)
			(stroke
				(width 0.1)
				(type default)
			)
			(layer "F.Fab")
		)
		(fp_line
			(start -0.2794 -0.1016)
			(end -0.2794 0.9906)
			(stroke
				(width 0.1)
				(type default)
			)
			(layer "F.Fab")
		)
		(fp_line
			(start 0.2794 0.9906)
			(end 0.2794 -0.1016)
			(stroke
				(width 0.1)
				(type default)
			)
			(layer "F.Fab")
		)
		(fp_line
			(start -0.2794 0.9906)
			(end 0.2794 0.9906)
			(stroke
				(width 0.1)
				(type default)
			)
			(layer "F.Fab")
		)
		(pad "1" smd rect
			(at 0 0 90)
			(size 0.508 0.508)
			(layers "F.Cu" "F.Mask" "F.Paste")
			(net "VSENSE_PVSA_CPU1_P")
		)
		(pad "2" smd rect
			(at 0 0.889 90)
			(size 0.508 0.508)
			(layers "F.Cu" "F.Mask" "F.Paste")
			(net "VSENSE_PVSA_CPU1_SKT_VSEN")
		)
		(zone
			(layer "F.Cu")
			(hatch none 0.5)
			(connect_pads
				(clearance 0)
			)
			(min_thickness 0.25)
			(keepout
				(tracks allowed)
				(vias not_allowed)
				(pads allowed)
				(copperpour not_allowed)
				(footprints allowed)
			)
			(placement
				(enabled no)
				(sheetname "")
			)
			(fill
				(thermal_gap 0.5)
				(thermal_bridge_width 0.5)
				(island_removal_mode 0)
			)
			(polygon
				(pts
					(xy 40.86225 -102.475284) (xy 40.86225 -102.983284) (xy 41.24325 -102.983284) (xy 41.24325 -102.475284)
				)
			)
		)
		(zone
			(layer "F.Cu")
			(hatch none 0.5)
			(connect_pads
				(clearance 0)
			)
			(min_thickness 0.25)
			(keepout
				(tracks not_allowed)
				(vias allowed)
				(pads allowed)
				(copperpour not_allowed)
				(footprints allowed)
			)
			(placement
				(enabled no)
				(sheetname "")
			)
			(fill
				(thermal_gap 0.5)
				(thermal_bridge_width 0.5)
				(island_removal_mode 0)
			)
			(polygon
				(pts
					(xy 41.24325 -102.475284) (xy 41.24325 -102.983284) (xy 40.86225 -102.983284) (xy 40.86225 -102.475284)
				)
			)
		)
	)
	(footprint ""
		(layer "F.Cu")
		(at 477.901 -36.6395 180)
		(property "Reference" "R8G24"
			(at 0 0 180)
			(layer "F.SilkS")
			(hide yes)
			(effects
				(font
					(size 1.27 1.27)
				)
			)
		)
		(property "Value" ""
			(at 0 0 180)
			(layer "F.Fab")
			(effects
				(font
					(size 1.27 1.27)
				)
			)
		)
		(duplicate_pad_numbers_are_jumpers no)
		(fp_poly
			(pts
				(xy -0.2794 -0.1016) (xy 0.2794 -0.1016) (xy 0.2794 0.9906) (xy -0.2794 0.9906)
			)
			(stroke
				(width 0)
				(type default)
			)
			(fill no)
			(layer "F.CrtYd")
		)
		(fp_line
			(start 0.2794 0.9906)
			(end 0.2794 -0.1016)
			(stroke
				(width 0.1)
				(type default)
			)
			(layer "F.Fab")
		)
		(fp_line
			(start 0.2794 -0.1016)
			(end -0.2794 -0.1016)
			(stroke
				(width 0.1)
				(type default)
			)
			(layer "F.Fab")
		)
		(fp_line
			(start -0.2794 0.9906)
			(end 0.2794 0.9906)
			(stroke
				(width 0.1)
				(type default)
			)
			(layer "F.Fab")
		)
		(fp_line
			(start -0.2794 -0.1016)
			(end -0.2794 0.9906)
			(stroke
				(width 0.1)
				(type default)
			)
			(layer "F.Fab")
		)
		(pad "1" smd rect
			(at 0 0 180)
			(size 0.508 0.508)
			(layers "F.Cu" "F.Mask" "F.Paste")
			(net "CLK_50M_CKMNG_PCH_10GBE_R")
		)
		(pad "2" smd rect
			(at 0 0.889 180)
			(size 0.508 0.508)
			(layers "F.Cu" "F.Mask" "F.Paste")
			(net "CLK_50M_CKMNG_PCH_10GBE")
		)
		(zone
			(layer "F.Cu")
			(hatch none 0.5)
			(connect_pads
				(clearance 0)
			)
			(min_thickness 0.25)
			(keepout
				(tracks not_allowed)
				(vias allowed)
				(pads allowed)
				(copperpour not_allowed)
				(footprints allowed)
			)
			(placement
				(enabled no)
				(sheetname "")
			)
			(fill
				(thermal_gap 0.5)
				(thermal_bridge_width 0.5)
				(island_removal_mode 0)
			)
			(polygon
				(pts
					(xy 478.155 -37.2745) (xy 477.647 -37.2745) (xy 477.647 -36.8935) (xy 478.155 -36.8935)
				)
			)
		)
		(zone
			(layer "F.Cu")
			(hatch none 0.5)
			(connect_pads
				(clearance 0)
			)
			(min_thickness 0.25)
			(keepout
				(tracks allowed)
				(vias not_allowed)
				(pads allowed)
				(copperpour not_allowed)
				(footprints allowed)
			)
			(placement
				(enabled no)
				(sheetname "")
			)
			(fill
				(thermal_gap 0.5)
				(thermal_bridge_width 0.5)
				(island_removal_mode 0)
			)
			(polygon
				(pts
					(xy 478.155 -36.8935) (xy 477.647 -36.8935) (xy 477.647 -37.2745) (xy 478.155 -37.2745)
				)
			)
		)
	)
)
